# T6G (Grand Teton) — schematic netlist excerpt (pin names and nets, part order shuffled) for the footprints in the layout excerpt that follows; sources: Cadence DE-HDL packaged netlist, KiCad conversion of 04192023_DAF0TMB3IC0_F0TG_MB_C_brd_V02_OCP.brd

PL46  Q_INDUCTOR  0.22UH/33A IND  pkg SMLF  page 223 : \1\ = IND_PVDDIO_P1_CPL0 ; \2\ = GND
PC505  Q_CAP  2.2UF 10V 10% X6S  pkg C0402  page 225 : A = PVDD11_S3_P1_VCC1 ; B = GND

(kicad_pcb
	(version 20260206)
	(generator "pcbnew")
	(generator_version "10.0")
	(general
		(thickness 1.6)
		(legacy_teardrops no)
	)
	(paper "A4")
	(title_block
		(title "04192023_DAF0TMB3IC0_F0TG_MB_C_brd_V02_OCP.brd")
		(comment 1 "Grand Teton / footprints 4368-4369 of 8354")
	)
	(layers
		(0 "F.Cu" signal "TOP")
		(4 "In1.Cu" signal "GND")
		(6 "In2.Cu" signal "IN1")
		(8 "In3.Cu" signal "GND1")
		(10 "In4.Cu" signal "IN2")
		(12 "In5.Cu" signal "GND2")
		(14 "In6.Cu" signal "IN3")
		(16 "In7.Cu" signal "GND3")
		(18 "In8.Cu" signal "VCC")
		(20 "In9.Cu" signal "VCC1")
		(22 "In10.Cu" signal "GND4")
		(24 "In11.Cu" signal "IN4")
		(26 "In12.Cu" signal "GND5")
		(28 "In13.Cu" signal "IN5")
		(30 "In14.Cu" signal "GND6")
		(32 "In15.Cu" signal "IN6")
		(34 "In16.Cu" signal "GND7")
		(2 "B.Cu" signal "BOTTOM")
		(9 "F.Adhes" user "F.Adhesive")
		(11 "B.Adhes" user "B.Adhesive")
		(13 "F.Paste" user "Package Geometry/Pastemask Top")
		(15 "B.Paste" user "Package Geometry/Pastemask Bottom")
		(5 "F.SilkS" user "Ref Des/Silkscreen Top")
		(7 "B.SilkS" user "Ref Des/Silkscreen Bottom")
		(1 "F.Mask" user "Board Geometry/Soldermask Top")
		(3 "B.Mask" user "Board Geometry/Soldermask Bottom")
		(17 "Dwgs.User" user "User.Drawings")
		(19 "Cmts.User" user "User.Comments")
		(21 "Eco1.User" user "User.Eco1")
		(23 "Eco2.User" user "User.Eco2")
		(25 "Edge.Cuts" user "Board Geometry/Outline")
		(27 "Margin" user)
		(31 "F.CrtYd" user "Package Geometry/Place Bound Top")
		(29 "B.CrtYd" user "Package Geometry/Place Bound Bottom")
		(35 "F.Fab" user "Ref Des/Assembly Top")
		(33 "B.Fab" user "Ref Des/Assembly Bottom")
	)
	(footprint ""
		(layer "F.Cu")
		(at 179.236878 -353.960684 90)
		(property "Reference" "PC505"
			(at 0 0 90)
			(layer "F.SilkS")
			(hide yes)
			(effects
				(font
					(size 1.27 1.27)
				)
			)
		)
		(property "Value" ""
			(at 0 0 90)
			(layer "F.Fab")
			(effects
				(font
					(size 1.27 1.27)
				)
			)
		)
		(duplicate_pad_numbers_are_jumpers no)
		(fp_line
			(start 0.7874 -0.4064)
			(end 0.7874 0.4064)
			(stroke
				(width 0.1524)
				(type default)
			)
			(layer "F.SilkS")
		)
		(fp_line
			(start -0.7874 -0.4064)
			(end 0.7874 -0.4064)
			(stroke
				(width 0.1524)
				(type default)
			)
			(layer "F.SilkS")
		)
		(fp_line
			(start 0.7874 0.4064)
			(end 0.420116 0.4064)
			(stroke
				(width 0.1524)
				(type default)
			)
			(layer "F.SilkS")
		)
		(fp_line
			(start -0.265684 0.4064)
			(end -0.7874 0.4064)
			(stroke
				(width 0.1524)
				(type default)
			)
			(layer "F.SilkS")
		)
		(fp_line
			(start -0.7874 0.4064)
			(end -0.7874 -0.4064)
			(stroke
				(width 0.1524)
				(type default)
			)
			(layer "F.SilkS")
		)
		(fp_line
			(start -0.12065 -0.305054)
			(end -0.12065 -0.2794)
			(stroke
				(width 0.1)
				(type default)
			)
			(layer "F.Fab")
		)
		(fp_line
			(start -0.67945 -0.305054)
			(end -0.12065 -0.305054)
			(stroke
				(width 0.1)
				(type default)
			)
			(layer "F.Fab")
		)
		(fp_line
			(start 0.67945 -0.3048)
			(end 0.67945 0.3048)
			(stroke
				(width 0.1)
				(type default)
			)
			(layer "F.Fab")
		)
		(fp_line
			(start 0.12065 -0.3048)
			(end 0.67945 -0.3048)
			(stroke
				(width 0.1)
				(type default)
			)
			(layer "F.Fab")
		)
		(fp_line
			(start 0.12065 -0.2794)
			(end 0.12065 -0.3048)
			(stroke
				(width 0.1)
				(type default)
			)
			(layer "F.Fab")
		)
		(fp_line
			(start -0.12065 -0.2794)
			(end 0.12065 -0.2794)
			(stroke
				(width 0.1)
				(type default)
			)
			(layer "F.Fab")
		)
		(fp_line
			(start 0.120396 0.2794)
			(end -0.12065 0.2794)
			(stroke
				(width 0.1)
				(type default)
			)
			(layer "F.Fab")
		)
		(fp_line
			(start -0.12065 0.2794)
			(end -0.12065 0.3048)
			(stroke
				(width 0.1)
				(type default)
			)
			(layer "F.Fab")
		)
		(fp_line
			(start 0.67945 0.3048)
			(end 0.120396 0.3048)
			(stroke
				(width 0.1)
				(type default)
			)
			(layer "F.Fab")
		)
		(fp_line
			(start 0.120396 0.3048)
			(end 0.120396 0.2794)
			(stroke
				(width 0.1)
				(type default)
			)
			(layer "F.Fab")
		)
		(fp_line
			(start -0.12065 0.3048)
			(end -0.67945 0.3048)
			(stroke
				(width 0.1)
				(type default)
			)
			(layer "F.Fab")
		)
		(fp_line
			(start -0.67945 0.3048)
			(end -0.67945 -0.305054)
			(stroke
				(width 0.1)
				(type default)
			)
			(layer "F.Fab")
		)
		(pad "1" smd circle
			(at -0.40005 0 90)
			(size 0 0)
			(layers "F.Cu" "F.Mask" "F.Paste")
			(net "PVDD11_S3_P1_VCC1")
		)
		(pad "2" smd circle
			(at 0.40005 0 90)
			(size 0 0)
			(layers "F.Cu" "F.Mask" "F.Paste")
			(net "GND")
		)
	)
	(footprint ""
		(layer "F.Cu")
		(at 21.075396 -339.223604 90)
		(property "Reference" "PL46"
			(at 0 -3.978148 90)
			(unlocked yes)
			(layer "F.SilkS")
			(effects
				(font
					(size 0.7874 0.5842)
					(thickness 0.1524)
				)
				(justify left)
			)
		)
		(property "Value" ""
			(at 0 0 90)
			(layer "F.Fab")
			(effects
				(font
					(size 1.27 1.27)
				)
			)
		)
		(duplicate_pad_numbers_are_jumpers no)
		(fp_line
			(start 3.24993 -3.24993)
			(end 3.24993 -2.2352)
			(stroke
				(width 0.1524)
				(type default)
			)
			(layer "F.SilkS")
		)
		(fp_line
			(start -3.24993 -3.24993)
			(end 3.24993 -3.24993)
			(stroke
				(width 0.1524)
				(type default)
			)
			(layer "F.SilkS")
		)
		(fp_line
			(start -3.24993 -2.2352)
			(end -3.24993 -3.24993)
			(stroke
				(width 0.1524)
				(type default)
			)
			(layer "F.SilkS")
		)
		(fp_line
			(start 3.24993 2.2352)
			(end 3.24993 3.24993)
			(stroke
				(width 0.1524)
				(type default)
			)
			(layer "F.SilkS")
		)
		(fp_line
			(start 3.24993 3.24993)
			(end -3.24993 3.24993)
			(stroke
				(width 0.1524)
				(type default)
			)
			(layer "F.SilkS")
		)
		(fp_line
			(start -3.24993 3.24993)
			(end -3.24993 2.2352)
			(stroke
				(width 0.1524)
				(type default)
			)
			(layer "F.SilkS")
		)
		(fp_line
			(start 3.24993 -3.24993)
			(end 3.24993 3.24993)
			(stroke
				(width 0.1)
				(type default)
			)
			(layer "F.Fab")
		)
		(fp_line
			(start -3.24993 -3.24993)
			(end 3.24993 -3.24993)
			(stroke
				(width 0.1)
				(type default)
			)
			(layer "F.Fab")
		)
		(fp_line
			(start 3.24993 3.24993)
			(end -3.24993 3.24993)
			(stroke
				(width 0.1)
				(type default)
			)
			(layer "F.Fab")
		)
		(fp_line
			(start -3.24993 3.24993)
			(end -3.24993 -3.24993)
			(stroke
				(width 0.1)
				(type default)
			)
			(layer "F.Fab")
		)
		(pad "1" smd rect
			(at -2.29997 0 90)
			(size 2.0066 4.2164)
			(layers "F.Cu" "F.Mask" "F.Paste")
			(net "IND_PVDDIO_P1_CPL0")
		)
		(pad "2" smd rect
			(at 2.29997 0 90)
			(size 2.0066 4.2164)
			(layers "F.Cu" "F.Mask" "F.Paste")
			(net "GND")
		)
	)
)
